FILE_TYPE=LIBRARY_PARTS;
primitive 'Q_INDUCTOR';
  pin
    '2':
      PIN_NUMBER='(2)';
      BIDIRECTIONAL='TRUE';
      INPUT_LOAD='(-0.01,0.01)';
      OUTPUT_LOAD='(1.0,-1.0)';
    '1':
      PIN_NUMBER='(1)';
      BIDIRECTIONAL='TRUE';
      INPUT_LOAD='(-0.01,0.01)';
      OUTPUT_LOAD='(1.0,-1.0)';
  end_pin;
  body
    PART_NAME='Q_INDUCTOR';
    BODY_NAME='Q_INDUCTOR';
    PHYS_DES_PREFIX='L';
    CLASS='IC';
  end_body;
end_primitive;

END.
